# Thunderbolt GPU Adapter — KiCad project settings (.kicad_pro: net classes, design rules, text variables)
{
  "board": {
    "3dviewports": [],
    "design_settings": {
      "defaults": {
        "apply_defaults_to_fp_fields": false,
        "apply_defaults_to_fp_shapes": false,
        "apply_defaults_to_fp_text": false,
        "board_outline_line_width": 0.1,
        "copper_line_width": 0.2,
        "copper_text_italic": false,
        "copper_text_size_h": 1.5,
        "copper_text_size_v": 1.5,
        "copper_text_thickness": 0.3,
        "copper_text_upright": false,
        "courtyard_line_width": 0.05,
        "dimension_precision": 4,
        "dimension_units": 3,
        "dimensions": {
          "arrow_length": 1270000,
          "extension_offset": 500000,
          "keep_text_aligned": true,
          "suppress_zeroes": false,
          "text_position": 0,
          "units_format": 1
        },
        "fab_line_width": 0.1,
        "fab_text_italic": false,
        "fab_text_size_h": 1.0,
        "fab_text_size_v": 1.0,
        "fab_text_thickness": 0.15,
        "fab_text_upright": false,
        "other_line_width": 0.15,
        "other_text_italic": false,
        "other_text_size_h": 1.0,
        "other_text_size_v": 1.0,
        "other_text_thickness": 0.15,
        "other_text_upright": false,
        "pads": {
          "drill": 0.75,
          "height": 2.6,
          "width": 1.3
        },
        "silk_line_width": 0.15,
        "silk_text_italic": false,
        "silk_text_size_h": 1.0,
        "silk_text_size_v": 1.0,
        "silk_text_thickness": 0.15,
        "silk_text_upright": false,
        "zones": {
          "45_degree_only": false,
          "min_clearance": 0.25
        }
      },
      "diff_pair_dimensions": [
        {
          "gap": 0.0,
          "via_gap": 0.0,
          "width": 0.0
        }
      ],
      "drc_exclusions": [],
      "meta": {
        "version": 2
      },
      "rule_severities": {
        "annular_width": "error",
        "clearance": "error",
        "connection_width": "warning",
        "copper_edge_clearance": "error",
        "copper_sliver": "warning",
        "courtyards_overlap": "error",
        "diff_pair_gap_out_of_range": "error",
        "diff_pair_uncoupled_length_too_long": "error",
        "drill_out_of_range": "error",
        "duplicate_footprints": "warning",
        "extra_footprint": "warning",
        "footprint": "error",
        "footprint_symbol_mismatch": "warning",
        "footprint_type_mismatch": "error",
        "hole_clearance": "error",
        "hole_near_hole": "error",
        "holes_co_located": "warning",
        "invalid_outline": "error",
        "isolated_copper": "warning",
        "item_on_disabled_layer": "error",
        "items_not_allowed": "error",
        "length_out_of_range": "error",
        "lib_footprint_issues": "warning",
        "lib_footprint_mismatch": "warning",
        "malformed_courtyard": "error",
        "microvia_drill_out_of_range": "error",
        "missing_courtyard": "warning",
        "missing_footprint": "warning",
        "net_conflict": "warning",
        "npth_inside_courtyard": "warning",
        "padstack": "error",
        "pth_inside_courtyard": "warning",
        "shorting_items": "error",
        "silk_edge_clearance": "warning",
        "silk_over_copper": "warning",
        "silk_overlap": "warning",
        "skew_out_of_range": "error",
        "solder_mask_bridge": "error",
        "starved_thermal": "error",
        "text_height": "warning",
        "text_thickness": "warning",
        "through_hole_pad_without_hole": "error",
        "too_many_vias": "error",
        "track_dangling": "warning",
        "track_width": "error",
        "tracks_crossing": "error",
        "unconnected_items": "error",
        "unresolved_variable": "error",
        "via_dangling": "warning",
        "zones_intersect": "error"
      },
      "rules": {
        "allow_blind_buried_vias": false,
        "allow_microvias": false,
        "max_error": 0.005,
        "min_clearance": 0.1,
        "min_connection": 0.0,
        "min_copper_edge_clearance": 0.0,
        "min_hole_clearance": 0.25,
        "min_hole_to_hole": 0.25,
        "min_microvia_diameter": 0.3,
        "min_microvia_drill": 0.1,
        "min_resolved_spokes": 2,
        "min_silk_clearance": 0.0,
        "min_text_height": 0.6,
        "min_text_thickness": 0.08,
        "min_through_hole_diameter": 0.1,
        "min_track_width": 0.1,
        "min_via_annular_width": 0.125,
        "min_via_diameter": 0.45,
        "solder_mask_clearance": 0.0,
        "solder_mask_min_width": 0.0,
        "solder_mask_to_copper_clearance": 0.0,
        "use_height_for_length_calcs": true
      },
      "teardrop_options": [
        {
          "td_onpadsmd": true,
          "td_onroundshapesonly": false,
          "td_ontrackend": false,
          "td_onviapad": true
        }
      ],
      "teardrop_parameters": [
        {
          "td_allow_use_two_tracks": true,
          "td_curve_segcount": 0,
          "td_height_ratio": 1.0,
          "td_length_ratio": 0.5,
          "td_maxheight": 2.0,
          "td_maxlen": 1.0,
          "td_on_pad_in_zone": false,
          "td_target_name": "td_round_shape",
          "td_width_to_size_filter_ratio": 0.9
        },
        {
          "td_allow_use_two_tracks": true,
          "td_curve_segcount": 0,
          "td_height_ratio": 1.0,
          "td_length_ratio": 0.5,
          "td_maxheight": 2.0,
          "td_maxlen": 1.0,
          "td_on_pad_in_zone": false,
          "td_target_name": "td_rect_shape",
          "td_width_to_size_filter_ratio": 0.9
        },
        {
          "td_allow_use_two_tracks": true,
          "td_curve_segcount": 0,
          "td_height_ratio": 1.0,
          "td_length_ratio": 0.5,
          "td_maxheight": 2.0,
          "td_maxlen": 1.0,
          "td_on_pad_in_zone": false,
          "td_target_name": "td_track_end",
          "td_width_to_size_filter_ratio": 0.9
        }
      ],
      "track_widths": [
        0.0,
        0.1,
        0.2,
        0.25,
        0.4,
        0.6
      ],
      "tuning_pattern_settings": {
        "diff_pair_defaults": {
          "corner_radius_percentage": 80,
          "corner_style": 1,
          "max_amplitude": 1.0,
          "min_amplitude": 0.2,
          "single_sided": false,
          "spacing": 1.0
        },
        "diff_pair_skew_defaults": {
          "corner_radius_percentage": 80,
          "corner_style": 1,
          "max_amplitude": 1.0,
          "min_amplitude": 0.2,
          "single_sided": false,
          "spacing": 0.6
        },
        "single_track_defaults": {
          "corner_radius_percentage": 80,
          "corner_style": 1,
          "max_amplitude": 1.0,
          "min_amplitude": 0.2,
          "single_sided": false,
          "spacing": 0.6
        }
      },
      "via_dimensions": [
        {
          "diameter": 0.0,
          "drill": 0.0
        }
      ],
      "zones_allow_external_fillets": false,
      "zones_use_no_outline": true
    },
    "ipc2581": {
      "dist": "",
      "distpn": "",
      "internal_id": "",
      "mfg": "",
      "mpn": ""
    },
    "layer_presets": [],
    "viewports": []
  },
  "boards": [],
  "cvpcb": {
    "equivalence_files": []
  },
  "erc": {
    "erc_exclusions": [],
    "meta": {
      "version": 0
    },
    "pin_map": [
      [
        0,
        0,
        0,
        0,
        0,
        0,
        1,
        0,
        0,
        0,
        0,
        2
      ],
      [
        0,
        2,
        0,
        1,
        0,
        0,
        1,
        0,
        2,
        2,
        2,
        2
      ],
      [
        0,
        0,
        0,
        0,
        0,
        0,
        1,
        0,
        1,
        0,
        1,
        2
      ],
      [
        0,
        1,
        0,
        0,
        0,
        0,
        1,
        1,
        2,
        1,
        1,
        2
      ],
      [
        0,
        0,
        0,
        0,
        0,
        0,
        1,
        0,
        0,
        0,
        0,
        2
      ],
      [
        0,
        0,
        0,
        0,
        0,
        0,
        0,
        0,
        0,
        0,
        0,
        2
      ],
      [
        1,
        1,
        1,
        1,
        1,
        0,
        1,
        1,
        1,
        1,
        1,
        2
      ],
      [
        0,
        0,
        0,
        1,
        0,
        0,
        1,
        0,
        0,
        0,
        0,
        2
      ],
      [
        0,
        2,
        1,
        2,
        0,
        0,
        1,
        0,
        2,
        2,
        2,
        2
      ],
      [
        0,
        2,
        0,
        1,
        0,
        0,
        1,
        0,
        2,
        0,
        0,
        2
      ],
      [
        0,
        2,
        1,
        1,
        0,
        0,
        1,
        0,
        2,
        0,
        0,
        2
      ],
      [
        2,
        2,
        2,
        2,
        2,
        2,
        2,
        2,
        2,
        2,
        2,
        2
      ]
    ],
    "rule_severities": {
      "bus_definition_conflict": "error",
      "bus_entry_needed": "error",
      "bus_to_bus_conflict": "error",
      "bus_to_net_conflict": "error",
      "conflicting_netclasses": "error",
      "different_unit_footprint": "error",
      "different_unit_net": "error",
      "duplicate_reference": "error",
      "duplicate_sheet_names": "error",
      "endpoint_off_grid": "warning",
      "extra_units": "error",
      "global_label_dangling": "warning",
      "hier_label_mismatch": "error",
      "label_dangling": "error",
      "lib_symbol_issues": "warning",
      "missing_bidi_pin": "warning",
      "missing_input_pin": "warning",
      "missing_power_pin": "error",
      "missing_unit": "warning",
      "multiple_net_names": "warning",
      "net_not_bus_member": "warning",
      "no_connect_connected": "warning",
      "no_connect_dangling": "warning",
      "pin_not_connected": "error",
      "pin_not_driven": "error",
      "pin_to_pin": "ignore",
      "power_pin_not_driven": "warning",
      "similar_labels": "warning",
      "simulation_model_issue": "ignore",
      "unannotated": "error",
      "unit_value_mismatch": "error",
      "unresolved_variable": "error",
      "wire_dangling": "error"
    }
  },
  "libraries": {
    "pinned_footprint_libs": [],
    "pinned_symbol_libs": []
  },
  "meta": {
    "filename": "thunderbolt-gpu-adapter.kicad_pro",
    "version": 1
  },
  "net_settings": {
    "classes": [
      {
        "bus_width": 12,
        "clearance": 0.1,
        "diff_pair_gap": 0.1,
        "diff_pair_via_gap": 0.25,
        "diff_pair_width": 0.1,
        "line_style": 0,
        "microvia_diameter": 0.3,
        "microvia_drill": 0.1,
        "name": "Default",
        "pcb_color": "rgba(0, 0, 0, 0.000)",
        "schematic_color": "rgba(0, 0, 0, 0.000)",
        "track_width": 0.1,
        "via_diameter": 0.45,
        "via_drill": 0.1,
        "wire_width": 6
      },
      {
        "bus_width": 12,
        "clearance": 0.1,
        "diff_pair_gap": 0.2,
        "diff_pair_via_gap": 0.25,
        "diff_pair_width": 0.2,
        "line_style": 0,
        "microvia_diameter": 0.3,
        "microvia_drill": 0.1,
        "name": "85Ohm-diff_PCIE3",
        "pcb_color": "rgba(0, 0, 0, 0.000)",
        "schematic_color": "rgba(0, 0, 0, 0.000)",
        "track_width": 0.1,
        "via_diameter": 0.45,
        "via_drill": 0.1,
        "wire_width": 6
      },
      {
        "bus_width": 12,
        "clearance": 0.1,
        "diff_pair_gap": 0.2,
        "diff_pair_via_gap": 0.25,
        "diff_pair_width": 0.2,
        "line_style": 0,
        "microvia_diameter": 0.3,
        "microvia_drill": 0.1,
        "name": "85Ohm-diff_USB4",
        "pcb_color": "rgba(0, 0, 0, 0.000)",
        "schematic_color": "rgba(0, 0, 0, 0.000)",
        "track_width": 0.1,
        "via_diameter": 0.45,
        "via_drill": 0.1,
        "wire_width": 6
      },
      {
        "bus_width": 12,
        "clearance": 0.1,
        "diff_pair_gap": 0.2,
        "diff_pair_via_gap": 0.25,
        "diff_pair_width": 0.2,
        "line_style": 0,
        "microvia_diameter": 0.3,
        "microvia_drill": 0.1,
        "name": "90Ohm-diff_USB2",
        "pcb_color": "rgba(0, 0, 0, 0.000)",
        "schematic_color": "rgba(0, 0, 0, 0.000)",
        "track_width": 0.1,
        "via_diameter": 0.45,
        "via_drill": 0.1,
        "wire_width": 6
      }
    ],
    "meta": {
      "version": 3
    },
    "net_colors": null,
    "netclass_assignments": null,
    "netclass_patterns": [
      {
        "netclass": "85Ohm-diff_PCIE3",
        "pattern": "*PCIE*_P"
      },
      {
        "netclass": "85Ohm-diff_PCIE3",
        "pattern": "*PCIE*_N"
      },
      {
        "netclass": "90Ohm-diff_USB2",
        "pattern": "USB*"
      },
      {
        "netclass": "85Ohm-diff_USB4",
        "pattern": "TB*"
      },
      {
        "netclass": "85Ohm-diff_PCIE3",
        "pattern": "/TB Controller/TX*"
      },
      {
        "netclass": "85Ohm-diff_USB4",
        "pattern": "/TB Controller/PA*"
      }
    ]
  },
  "pcbnew": {
    "last_paths": {
      "gencad": "",
      "idf": "",
      "netlist": "",
      "plot": "",
      "pos_files": "",
      "specctra_dsn": "",
      "step": "thunderbolt-gpu-adapter.step",
      "svg": "",
      "vrml": "thunderbolt-gpu-adapter.wrl"
    },
    "page_layout_descr_file": ""
  },
  "schematic": {
    "annotate_start_num": 0,
    "bom_export_filename": "",
    "bom_fmt_presets": [],
    "bom_fmt_settings": {
      "field_delimiter": ",",
      "keep_line_breaks": false,
      "keep_tabs": false,
      "name": "CSV",
      "ref_delimiter": ",",
      "ref_range_delimiter": "",
      "string_delimiter": "\""
    },
    "bom_presets": [],
    "bom_settings": {
      "exclude_dnp": false,
      "fields_ordered": [
        {
          "group_by": false,
          "label": "Reference",
          "name": "Reference",
          "show": true
        },
        {
          "group_by": true,
          "label": "Value",
          "name": "Value",
          "show": true
        },
        {
          "group_by": false,
          "label": "Datasheet",
          "name": "Datasheet",
          "show": true
        },
        {
          "group_by": false,
          "label": "Footprint",
          "name": "Footprint",
          "show": true
        },
        {
          "group_by": false,
          "label": "Qty",
          "name": "${QUANTITY}",
          "show": true
        },
        {
          "group_by": true,
          "label": "DNP",
          "name": "${DNP}",
          "show": true
        }
      ],
      "filter_string": "",
      "group_symbols": true,
      "name": "Grouped By Value",
      "sort_asc": true,
      "sort_field": "Reference"
    },
    "connection_grid_size": 50.0,
    "drawing": {
      "dashed_lines_dash_length_ratio": 12.0,
      "dashed_lines_gap_length_ratio": 3.0,
      "default_line_thickness": 6.0,
      "default_text_size": 50.0,
      "field_names": [],
      "intersheets_ref_own_page": false,
      "intersheets_ref_prefix": "",
      "intersheets_ref_short": false,
      "intersheets_ref_show": false,
      "intersheets_ref_suffix": "",
      "junction_size_choice": 3,
      "label_size_ratio": 0.375,
      "operating_point_overlay_i_precision": 3,
      "operating_point_overlay_i_range": "~A",
      "operating_point_overlay_v_precision": 3,
      "operating_point_overlay_v_range": "~V",
      "overbar_offset_ratio": 1.23,
      "pin_symbol_size": 25.0,
      "text_offset_ratio": 0.15
    },
    "legacy_lib_dir": "",
    "legacy_lib_list": [],
    "meta": {
      "version": 1
    },
    "net_format_name": "",
    "ngspice": {
      "fix_include_paths": true,
      "fix_passive_vals": false,
      "meta": {
        "version": 0
      },
      "model_mode": 0,
      "workbook_filename": ""
    },
    "page_layout_descr_file": "",
    "plot_directory": "",
    "spice_adjust_passive_values": false,
    "spice_current_sheet_as_root": false,
    "spice_external_command": "spice \"%I\"",
    "spice_model_current_sheet_as_root": true,
    "spice_save_all_currents": false,
    "spice_save_all_dissipations": false,
    "spice_save_all_voltages": false,
    "subpart_first_id": 65,
    "subpart_id_separator": 0
  },
  "sheets": [
    [
      "",
      "Root"
    ],
    [
      "",
      "Connectors"
    ],
    [
      "",
      "Power"
    ],
    [
      "",
      "Thunderbolt Controller - Power"
    ],
    [
      "",
      "TB Controller"
    ]
  ],
  "text_variables": {}
}
